# BASEBOARD_FAB2 (Tioga Pass) — schematic netlist excerpt (pin names and nets, part order shuffled) for the footprints in the layout excerpt that follows; sources: Cadence DE-HDL packaged netlist, KiCad conversion of Wiwynn_Tioga_Pass_MB.brd

EU4A2  MIC5166  IC  pkg DFN  page 230
  VREF  = VR_PVTT_KLM_VREF
  BIAS  = VR_PVTT_KLM_BIAS
  AGND  = GND
  VDDQ  = VSENSE_PVDDQ_KLM_VTT
  PG  = PWRGD_PVTT_KLM_CPU1_R
  SNS  = VR_PVTT_KLM_SNS
  EN  = FM_PVTT_KLM_EN_R
  PGND  = GND
  VTT  = PVTT_KLM
  VIN  = PVDDQ_KLM
  THPAD  = GND

XBT8G1  VERT_BATT_3PIN  3PVERT  pkg PIP  page 196
  P1  = P3V_BAT_SOURCE
  P2  = P3V_BAT_SOURCE
  N  = GND

(kicad_pcb
	(version 20260206)
	(generator "pcbnew")
	(generator_version "10.0")
	(general
		(thickness 1.6)
		(legacy_teardrops no)
	)
	(paper "A4")
	(title_block
		(title "Wiwynn_Tioga_Pass_MB.brd")
		(comment 1 "Tioga Pass / footprints 945-946 of 4770")
	)
	(layers
		(0 "F.Cu" signal "TOP")
		(4 "In1.Cu" signal "L2GND")
		(6 "In2.Cu" signal "L3")
		(8 "In3.Cu" signal "L4GND")
		(10 "In4.Cu" signal "L5")
		(12 "In5.Cu" signal "L6GND")
		(14 "In6.Cu" signal "L7VCC")
		(16 "In7.Cu" signal "L8VCC")
		(18 "In8.Cu" signal "L9GND")
		(20 "In9.Cu" signal "L10")
		(22 "In10.Cu" signal "L11GND")
		(24 "In11.Cu" signal "L12")
		(26 "In12.Cu" signal "L13GND")
		(2 "B.Cu" signal "BOTTOM")
		(9 "F.Adhes" user "F.Adhesive")
		(11 "B.Adhes" user "B.Adhesive")
		(13 "F.Paste" user "Package Geometry/Pastemask Top")
		(15 "B.Paste" user "Package Geometry/Pastemask Bottom")
		(5 "F.SilkS" user "Ref Des/Silkscreen Top")
		(7 "B.SilkS" user "Ref Des/Silkscreen Bottom")
		(1 "F.Mask" user "Board Geometry/Soldermask Top")
		(3 "B.Mask" user "Board Geometry/Soldermask Bottom")
		(17 "Dwgs.User" user "User.Drawings")
		(19 "Cmts.User" user "User.Comments")
		(21 "Eco1.User" user "User.Eco1")
		(23 "Eco2.User" user "User.Eco2")
		(25 "Edge.Cuts" user "Board Geometry/Outline")
		(27 "Margin" user)
		(31 "F.CrtYd" user "Package Geometry/Place Bound Top")
		(29 "B.CrtYd" user "Package Geometry/Place Bound Bottom")
		(35 "F.Fab" user "Ref Des/Assembly Top")
		(33 "B.Fab" user "Ref Des/Assembly Bottom")
	)
	(footprint ""
		(layer "F.Cu")
		(at 423.421048 3.679952 180)
		(property "Reference" "XBT8G1"
			(at 7.65556 5.53847 0)
			(unlocked yes)
			(layer "F.SilkS")
			(effects
				(font
					(size 0.7874 0.5842)
					(thickness 0.1524)
				)
				(justify left)
			)
		)
		(property "Value" ""
			(at 0 0 180)
			(layer "F.Fab")
			(effects
				(font
					(size 1.27 1.27)
				)
			)
		)
		(duplicate_pad_numbers_are_jumpers no)
		(fp_line
			(start 16.774922 4.824984)
			(end -6.774942 4.824984)
			(stroke
				(width 0.1524)
				(type default)
			)
			(layer "F.SilkS")
		)
		(fp_line
			(start 16.774922 -1.225042)
			(end 16.774922 4.824984)
			(stroke
				(width 0.1524)
				(type default)
			)
			(layer "F.SilkS")
		)
		(fp_line
			(start -2.2098 -3.2512)
			(end -2.2098 -1.9812)
			(stroke
				(width 0.1524)
				(type default)
			)
			(layer "F.SilkS")
		)
		(fp_line
			(start -2.8448 -2.6162)
			(end -1.5748 -2.6162)
			(stroke
				(width 0.1524)
				(type default)
			)
			(layer "F.SilkS")
		)
		(fp_line
			(start -6.774942 4.824984)
			(end -6.774942 -1.225042)
			(stroke
				(width 0.1524)
				(type default)
			)
			(layer "F.SilkS")
		)
		(fp_line
			(start -6.774942 -1.225042)
			(end 16.774922 -1.225042)
			(stroke
				(width 0.1524)
				(type default)
			)
			(layer "F.SilkS")
		)
		(fp_poly
			(pts
				(xy -6.774942 -1.225042) (xy -6.774942 4.824984) (xy 16.774922 4.824984) (xy 16.774922 -1.225042)
			)
			(stroke
				(width 0)
				(type default)
			)
			(fill no)
			(layer "F.CrtYd")
		)
		(fp_line
			(start 16.774922 4.824984)
			(end 16.774922 -1.225042)
			(stroke
				(width 0.1)
				(type default)
			)
			(layer "F.Fab")
		)
		(fp_line
			(start 16.774922 -1.225042)
			(end -6.774942 -1.225042)
			(stroke
				(width 0.1)
				(type default)
			)
			(layer "F.Fab")
		)
		(fp_line
			(start -2.2098 -3.2512)
			(end -2.2098 -1.9812)
			(stroke
				(width 0.1)
				(type default)
			)
			(layer "F.Fab")
		)
		(fp_line
			(start -2.8448 -2.6162)
			(end -1.5748 -2.6162)
			(stroke
				(width 0.1)
				(type default)
			)
			(layer "F.Fab")
		)
		(fp_line
			(start -6.774942 4.824984)
			(end 16.774922 4.824984)
			(stroke
				(width 0.1)
				(type default)
			)
			(layer "F.Fab")
		)
		(fp_line
			(start -6.774942 -1.225042)
			(end -6.774942 4.824984)
			(stroke
				(width 0.1)
				(type default)
			)
			(layer "F.Fab")
		)
		(pad "1" thru_hole rect
			(at 0 0 180)
			(size 1.3716 1.3716)
			(drill 0.9906)
			(layers "*.Cu" "*.Mask")
			(remove_unused_layers no)
			(net "P3V_BAT_SOURCE")
			(clearance 0.127)
			(thermal_gap 0.127)
			(padstack
				(mode front_inner_back)
				(layer "Inner"
					(shape circle)
					(size 1.3716 1.3716)
					(clearance 0.127)
				)
				(layer "B.Cu"
					(shape rect)
					(size 1.3716 1.3716)
					(clearance 0.127)
				)
			)
		)
		(pad "2" thru_hole circle
			(at 9.99998 0 180)
			(size 1.3716 1.3716)
			(drill 0.9906)
			(layers "*.Cu" "*.Mask")
			(remove_unused_layers no)
			(net "P3V_BAT_SOURCE")
			(clearance 0.127)
			(thermal_gap 0.127)
		)
		(pad "3" thru_hole circle
			(at 4.99999 3.599942 180)
			(size 1.3716 1.3716)
			(drill 0.9906)
			(layers "*.Cu" "*.Mask")
			(remove_unused_layers no)
			(net "GND")
			(clearance 0.127)
			(thermal_gap 0.127)
		)
	)
	(footprint ""
		(layer "F.Cu")
		(at 171.983146 -146.429222 180)
		(property "Reference" "EU4A2"
			(at 0.787146 -1.904492 0)
			(unlocked yes)
			(layer "F.SilkS")
			(effects
				(font
					(size 0.7874 0.5842)
					(thickness 0.1524)
				)
				(justify left)
			)
		)
		(property "Value" ""
			(at 0 0 180)
			(layer "F.Fab")
			(effects
				(font
					(size 1.27 1.27)
				)
			)
		)
		(duplicate_pad_numbers_are_jumpers no)
		(fp_circle
			(center -0.835152 -0.417322)
			(end -0.962152 -0.417322)
			(stroke
				(width 0.254)
				(type default)
			)
			(fill no)
			(layer "F.SilkS")
		)
		(fp_poly
			(pts
				(xy -0.064516 -1.0922) (xy -0.064516 -0.3302) (xy 0.697484 -1.0922)
			)
			(stroke
				(width 0)
				(type default)
			)
			(fill yes)
			(layer "F.SilkS")
		)
		(fp_rect
			(start 0.597408 2.295398)
			(end 2.273808 -0.295402)
			(stroke
				(width 0)
				(type default)
			)
			(fill yes)
			(layer "F.Paste")
		)
		(fp_rect
			(start -0.064516 2.500122)
			(end 2.935478 -0.500126)
			(stroke
				(width 0)
				(type default)
			)
			(fill no)
			(layer "F.CrtYd")
		)
		(fp_line
			(start 2.935478 2.500122)
			(end -0.064516 2.500122)
			(stroke
				(width 0.1)
				(type default)
			)
			(layer "F.Fab")
		)
		(fp_line
			(start 2.935478 -0.500126)
			(end 2.935478 2.500122)
			(stroke
				(width 0.1)
				(type default)
			)
			(layer "F.Fab")
		)
		(fp_line
			(start -0.064516 2.500122)
			(end -0.064516 -0.500126)
			(stroke
				(width 0.1)
				(type default)
			)
			(layer "F.Fab")
		)
		(fp_line
			(start -0.064516 -0.500126)
			(end 2.935478 -0.500126)
			(stroke
				(width 0.1)
				(type default)
			)
			(layer "F.Fab")
		)
		(fp_circle
			(center -0.835152 -0.417322)
			(end -0.962152 -0.417322)
			(stroke
				(width 0.254)
				(type default)
			)
			(fill no)
			(layer "F.Fab")
		)
		(pad "1" smd rect
			(at 0 0 180)
			(size 0.6858 0.3048)
			(layers "F.Cu" "F.Mask" "F.Paste")
			(net "VR_PVTT_KLM_VREF")
		)
		(pad "2" smd rect
			(at 0 0.500126 180)
			(size 0.6858 0.3048)
			(layers "F.Cu" "F.Mask" "F.Paste")
			(net "VR_PVTT_KLM_BIAS")
		)
		(pad "3" smd rect
			(at 0 0.999998 180)
			(size 0.6858 0.3048)
			(layers "F.Cu" "F.Mask" "F.Paste")
			(net "GND")
		)
		(pad "4" smd rect
			(at 0 1.500124 180)
			(size 0.6858 0.3048)
			(layers "F.Cu" "F.Mask" "F.Paste")
			(net "VSENSE_PVDDQ_KLM_VTT")
		)
		(pad "5" smd rect
			(at 0 1.999996 180)
			(size 0.6858 0.3048)
			(layers "F.Cu" "F.Mask" "F.Paste")
			(net "PWRGD_PVTT_KLM_CPU1_R")
		)
		(pad "6" smd rect
			(at 2.871216 1.999996 180)
			(size 0.6858 0.3048)
			(layers "F.Cu" "F.Mask" "F.Paste")
			(net "VR_PVTT_KLM_SNS")
		)
		(pad "7" smd rect
			(at 2.871216 1.500124 180)
			(size 0.6858 0.3048)
			(layers "F.Cu" "F.Mask" "F.Paste")
			(net "FM_PVTT_KLM_EN_R")
		)
		(pad "8" smd rect
			(at 2.871216 0.999998 180)
			(size 0.6858 0.3048)
			(layers "F.Cu" "F.Mask" "F.Paste")
			(net "GND")
		)
		(pad "9" smd rect
			(at 2.871216 0.500126 180)
			(size 0.6858 0.3048)
			(layers "F.Cu" "F.Mask" "F.Paste")
			(net "PVTT_KLM")
		)
		(pad "10" smd rect
			(at 2.871216 0 180)
			(size 0.6858 0.3048)
			(layers "F.Cu" "F.Mask" "F.Paste")
			(net "PVDDQ_KLM")
		)
		(pad "11" smd rect
			(at 1.435608 0.999998 180)
			(size 1.6764 2.5908)
			(layers "F.Cu" "F.Mask" "F.Paste")
			(net "GND")
		)
	)
)
